(kicad_pcb
	(version 20260206)
	(generator "pcbnew")
	(generator_version "10.0")
	(general
		(thickness 1.6)
		(legacy_teardrops no)
	)
	(paper "A4")
	(title_block
		(title "04192023_DAF0TMB3IC0_F0TG_MB_C_brd_V02_OCP.brd")
		(comment 1 "Grand Teton / footprints 4811-4817 of 8354")
	)
	(layers
		(0 "F.Cu" signal "TOP")
		(4 "In1.Cu" signal "GND")
		(6 "In2.Cu" signal "IN1")
		(8 "In3.Cu" signal "GND1")
		(10 "In4.Cu" signal "IN2")
		(12 "In5.Cu" signal "GND2")
		(14 "In6.Cu" signal "IN3")
		(16 "In7.Cu" signal "GND3")
		(18 "In8.Cu" signal "VCC")
		(20 "In9.Cu" signal "VCC1")
		(22 "In10.Cu" signal "GND4")
		(24 "In11.Cu" signal "IN4")
		(26 "In12.Cu" signal "GND5")
		(28 "In13.Cu" signal "IN5")
		(30 "In14.Cu" signal "GND6")
		(32 "In15.Cu" signal "IN6")
		(34 "In16.Cu" signal "GND7")
		(2 "B.Cu" signal "BOTTOM")
		(9 "F.Adhes" user "F.Adhesive")
		(11 "B.Adhes" user "B.Adhesive")
		(13 "F.Paste" user "Package Geometry/Pastemask Top")
		(15 "B.Paste" user "Package Geometry/Pastemask Bottom")
		(5 "F.SilkS" user "Ref Des/Silkscreen Top")
		(7 "B.SilkS" user "Ref Des/Silkscreen Bottom")
		(1 "F.Mask" user "Board Geometry/Soldermask Top")
		(3 "B.Mask" user "Board Geometry/Soldermask Bottom")
		(17 "Dwgs.User" user "User.Drawings")
		(19 "Cmts.User" user "User.Comments")
		(21 "Eco1.User" user "User.Eco1")
		(23 "Eco2.User" user "User.Eco2")
		(25 "Edge.Cuts" user "Board Geometry/Outline")
		(27 "Margin" user)
		(31 "F.CrtYd" user "Package Geometry/Place Bound Top")
		(29 "B.CrtYd" user "Package Geometry/Place Bound Bottom")
		(35 "F.Fab" user "Ref Des/Assembly Top")
		(33 "B.Fab" user "Ref Des/Assembly Bottom")
	)
	(footprint ""
		(layer "F.Cu")
		(at 277.352252 -117.50167)
		(property "Reference" "R3582"
			(at 0 0 0)
			(layer "F.SilkS")
			(hide yes)
			(effects
				(font
					(size 1.27 1.27)
				)
			)
		)
		(property "Value" ""
			(at 0 0 0)
			(layer "F.Fab")
			(effects
				(font
					(size 1.27 1.27)
				)
			)
		)
		(duplicate_pad_numbers_are_jumpers no)
		(fp_line
			(start -0.7874 -0.4064)
			(end 0.7874 -0.4064)
			(stroke
				(width 0.1524)
				(type default)
			)
			(layer "F.SilkS")
		)
		(fp_line
			(start -0.7874 0.4064)
			(end -0.7874 -0.4064)
			(stroke
				(width 0.1524)
				(type default)
			)
			(layer "F.SilkS")
		)
		(fp_line
			(start 0.7874 -0.4064)
			(end 0.7874 0.4064)
			(stroke
				(width 0.1524)
				(type default)
			)
			(layer "F.SilkS")
		)
		(fp_line
			(start 0.7874 0.4064)
			(end -0.7874 0.4064)
			(stroke
				(width 0.1524)
				(type default)
			)
			(layer "F.SilkS")
		)
		(fp_line
			(start -0.67945 -0.305054)
			(end -0.12065 -0.305054)
			(stroke
				(width 0.1)
				(type default)
			)
			(layer "F.Fab")
		)
		(fp_line
			(start -0.67945 0.3048)
			(end -0.67945 -0.305054)
			(stroke
				(width 0.1)
				(type default)
			)
			(layer "F.Fab")
		)
		(fp_line
			(start -0.12065 -0.305054)
			(end -0.12065 -0.2794)
			(stroke
				(width 0.1)
				(type default)
			)
			(layer "F.Fab")
		)
		(fp_line
			(start -0.12065 -0.2794)
			(end 0.12065 -0.2794)
			(stroke
				(width 0.1)
				(type default)
			)
			(layer "F.Fab")
		)
		(fp_line
			(start -0.12065 0.2794)
			(end -0.12065 0.3048)
			(stroke
				(width 0.1)
				(type default)
			)
			(layer "F.Fab")
		)
		(fp_line
			(start -0.12065 0.3048)
			(end -0.67945 0.3048)
			(stroke
				(width 0.1)
				(type default)
			)
			(layer "F.Fab")
		)
		(fp_line
			(start 0.120396 0.2794)
			(end -0.12065 0.2794)
			(stroke
				(width 0.1)
				(type default)
			)
			(layer "F.Fab")
		)
		(fp_line
			(start 0.120396 0.3048)
			(end 0.120396 0.2794)
			(stroke
				(width 0.1)
				(type default)
			)
			(layer "F.Fab")
		)
		(fp_line
			(start 0.12065 -0.3048)
			(end 0.67945 -0.3048)
			(stroke
				(width 0.1)
				(type default)
			)
			(layer "F.Fab")
		)
		(fp_line
			(start 0.12065 -0.2794)
			(end 0.12065 -0.3048)
			(stroke
				(width 0.1)
				(type default)
			)
			(layer "F.Fab")
		)
		(fp_line
			(start 0.67945 -0.3048)
			(end 0.67945 0.3048)
			(stroke
				(width 0.1)
				(type default)
			)
			(layer "F.Fab")
		)
		(fp_line
			(start 0.67945 0.3048)
			(end 0.120396 0.3048)
			(stroke
				(width 0.1)
				(type default)
			)
			(layer "F.Fab")
		)
		(pad "1" smd circle
			(at -0.40005 0)
			(size 0 0)
			(layers "F.Cu" "F.Mask" "F.Paste")
			(net "P3V3_AUX")
		)
		(pad "2" smd circle
			(at 0.40005 0)
			(size 0 0)
			(layers "F.Cu" "F.Mask" "F.Paste")
			(net "SMB_IOEXP_3V3AUX_SCL")
		)
	)
	(footprint ""
		(layer "F.Cu")
		(at 163.953444 -373.03583 -90)
		(property "Reference" "C750"
			(at 0 0 270)
			(layer "F.SilkS")
			(hide yes)
			(effects
				(font
					(size 1.27 1.27)
				)
			)
		)
		(property "Value" ""
			(at 0 0 270)
			(layer "F.Fab")
			(effects
				(font
					(size 1.27 1.27)
				)
			)
		)
		(duplicate_pad_numbers_are_jumpers no)
		(fp_line
			(start -0.299974 0.150114)
			(end -0.299974 -0.150114)
			(stroke
				(width 0.1)
				(type default)
			)
			(layer "F.Fab")
		)
		(fp_line
			(start 0.299974 0.150114)
			(end -0.299974 0.150114)
			(stroke
				(width 0.1)
				(type default)
			)
			(layer "F.Fab")
		)
		(fp_line
			(start -0.299974 -0.150114)
			(end 0.299974 -0.150114)
			(stroke
				(width 0.1)
				(type default)
			)
			(layer "F.Fab")
		)
		(fp_line
			(start 0.299974 -0.150114)
			(end 0.299974 0.150114)
			(stroke
				(width 0.1)
				(type default)
			)
			(layer "F.Fab")
		)
		(pad "1" smd rect
			(at -0.2667 0 270)
			(size 0.3048 0.381)
			(layers "F.Cu" "F.Mask" "F.Paste")
			(net "P5E_CPU1_P2_TX_C_DN<11>")
		)
		(pad "2" smd rect
			(at 0.2667 0 270)
			(size 0.3048 0.381)
			(layers "F.Cu" "F.Mask" "F.Paste")
			(net "P5E_CPU1_P2_TX_DN<11>")
		)
	)
	(footprint ""
		(layer "F.Cu")
		(at 442.233558 -169.726864 180)
		(property "Reference" "R5017"
			(at 0 0 180)
			(layer "F.SilkS")
			(hide yes)
			(effects
				(font
					(size 1.27 1.27)
				)
			)
		)
		(property "Value" ""
			(at 0 0 180)
			(layer "F.Fab")
			(effects
				(font
					(size 1.27 1.27)
				)
			)
		)
		(duplicate_pad_numbers_are_jumpers no)
		(fp_line
			(start 0.7874 0.4064)
			(end -0.7874 0.4064)
			(stroke
				(width 0.1524)
				(type default)
			)
			(layer "F.SilkS")
		)
		(fp_line
			(start 0.7874 -0.4064)
			(end 0.7874 0.4064)
			(stroke
				(width 0.1524)
				(type default)
			)
			(layer "F.SilkS")
		)
		(fp_line
			(start -0.7874 0.4064)
			(end -0.7874 -0.4064)
			(stroke
				(width 0.1524)
				(type default)
			)
			(layer "F.SilkS")
		)
		(fp_line
			(start -0.7874 -0.4064)
			(end 0.7874 -0.4064)
			(stroke
				(width 0.1524)
				(type default)
			)
			(layer "F.SilkS")
		)
		(fp_line
			(start 0.67945 0.3048)
			(end 0.120396 0.3048)
			(stroke
				(width 0.1)
				(type default)
			)
			(layer "F.Fab")
		)
		(fp_line
			(start 0.67945 -0.3048)
			(end 0.67945 0.3048)
			(stroke
				(width 0.1)
				(type default)
			)
			(layer "F.Fab")
		)
		(fp_line
			(start 0.12065 -0.2794)
			(end 0.12065 -0.3048)
			(stroke
				(width 0.1)
				(type default)
			)
			(layer "F.Fab")
		)
		(fp_line
			(start 0.12065 -0.3048)
			(end 0.67945 -0.3048)
			(stroke
				(width 0.1)
				(type default)
			)
			(layer "F.Fab")
		)
		(fp_line
			(start 0.120396 0.3048)
			(end 0.120396 0.2794)
			(stroke
				(width 0.1)
				(type default)
			)
			(layer "F.Fab")
		)
		(fp_line
			(start 0.120396 0.2794)
			(end -0.12065 0.2794)
			(stroke
				(width 0.1)
				(type default)
			)
			(layer "F.Fab")
		)
		(fp_line
			(start -0.12065 0.3048)
			(end -0.67945 0.3048)
			(stroke
				(width 0.1)
				(type default)
			)
			(layer "F.Fab")
		)
		(fp_line
			(start -0.12065 0.2794)
			(end -0.12065 0.3048)
			(stroke
				(width 0.1)
				(type default)
			)
			(layer "F.Fab")
		)
		(fp_line
			(start -0.12065 -0.2794)
			(end 0.12065 -0.2794)
			(stroke
				(width 0.1)
				(type default)
			)
			(layer "F.Fab")
		)
		(fp_line
			(start -0.12065 -0.305054)
			(end -0.12065 -0.2794)
			(stroke
				(width 0.1)
				(type default)
			)
			(layer "F.Fab")
		)
		(fp_line
			(start -0.67945 0.3048)
			(end -0.67945 -0.305054)
			(stroke
				(width 0.1)
				(type default)
			)
			(layer "F.Fab")
		)
		(fp_line
			(start -0.67945 -0.305054)
			(end -0.12065 -0.305054)
			(stroke
				(width 0.1)
				(type default)
			)
			(layer "F.Fab")
		)
		(pad "1" smd circle
			(at -0.40005 0 180)
			(size 0 0)
			(layers "F.Cu" "F.Mask" "F.Paste")
			(net "PVDD11_S3_P0")
		)
		(pad "2" smd circle
			(at 0.40005 0 180)
			(size 0 0)
			(layers "F.Cu" "F.Mask" "F.Paste")
			(net "I3C_SCM_1_R_SDA")
		)
	)
	(footprint ""
		(layer "F.Cu")
		(at 277.352252 -125.638814)
		(property "Reference" "R320"
			(at 0 0 0)
			(layer "F.SilkS")
			(hide yes)
			(effects
				(font
					(size 1.27 1.27)
				)
			)
		)
		(property "Value" ""
			(at 0 0 0)
			(layer "F.Fab")
			(effects
				(font
					(size 1.27 1.27)
				)
			)
		)
		(duplicate_pad_numbers_are_jumpers no)
		(fp_line
			(start -0.7874 -0.4064)
			(end 0.7874 -0.4064)
			(stroke
				(width 0.1524)
				(type default)
			)
			(layer "F.SilkS")
		)
		(fp_line
			(start -0.7874 0.4064)
			(end -0.7874 -0.4064)
			(stroke
				(width 0.1524)
				(type default)
			)
			(layer "F.SilkS")
		)
		(fp_line
			(start 0.7874 -0.4064)
			(end 0.7874 0.4064)
			(stroke
				(width 0.1524)
				(type default)
			)
			(layer "F.SilkS")
		)
		(fp_line
			(start 0.7874 0.4064)
			(end -0.7874 0.4064)
			(stroke
				(width 0.1524)
				(type default)
			)
			(layer "F.SilkS")
		)
		(fp_line
			(start -0.67945 -0.305054)
			(end -0.12065 -0.305054)
			(stroke
				(width 0.1)
				(type default)
			)
			(layer "F.Fab")
		)
		(fp_line
			(start -0.67945 0.3048)
			(end -0.67945 -0.305054)
			(stroke
				(width 0.1)
				(type default)
			)
			(layer "F.Fab")
		)
		(fp_line
			(start -0.12065 -0.305054)
			(end -0.12065 -0.2794)
			(stroke
				(width 0.1)
				(type default)
			)
			(layer "F.Fab")
		)
		(fp_line
			(start -0.12065 -0.2794)
			(end 0.12065 -0.2794)
			(stroke
				(width 0.1)
				(type default)
			)
			(layer "F.Fab")
		)
		(fp_line
			(start -0.12065 0.2794)
			(end -0.12065 0.3048)
			(stroke
				(width 0.1)
				(type default)
			)
			(layer "F.Fab")
		)
		(fp_line
			(start -0.12065 0.3048)
			(end -0.67945 0.3048)
			(stroke
				(width 0.1)
				(type default)
			)
			(layer "F.Fab")
		)
		(fp_line
			(start 0.120396 0.2794)
			(end -0.12065 0.2794)
			(stroke
				(width 0.1)
				(type default)
			)
			(layer "F.Fab")
		)
		(fp_line
			(start 0.120396 0.3048)
			(end 0.120396 0.2794)
			(stroke
				(width 0.1)
				(type default)
			)
			(layer "F.Fab")
		)
		(fp_line
			(start 0.12065 -0.3048)
			(end 0.67945 -0.3048)
			(stroke
				(width 0.1)
				(type default)
			)
			(layer "F.Fab")
		)
		(fp_line
			(start 0.12065 -0.2794)
			(end 0.12065 -0.3048)
			(stroke
				(width 0.1)
				(type default)
			)
			(layer "F.Fab")
		)
		(fp_line
			(start 0.67945 -0.3048)
			(end 0.67945 0.3048)
			(stroke
				(width 0.1)
				(type default)
			)
			(layer "F.Fab")
		)
		(fp_line
			(start 0.67945 0.3048)
			(end 0.120396 0.3048)
			(stroke
				(width 0.1)
				(type default)
			)
			(layer "F.Fab")
		)
		(pad "1" smd circle
			(at -0.40005 0)
			(size 0 0)
			(layers "F.Cu" "F.Mask" "F.Paste")
			(net "P3V3_AUX")
		)
		(pad "2" smd circle
			(at 0.40005 0)
			(size 0 0)
			(layers "F.Cu" "F.Mask" "F.Paste")
			(net "PCA9548_PCIE3_ADDR0")
		)
	)
	(footprint ""
		(layer "F.Cu")
		(at 102.811834 -176.438052 90)
		(property "Reference" "PC293_4"
			(at 0 0 90)
			(layer "F.SilkS")
			(hide yes)
			(effects
				(font
					(size 1.27 1.27)
				)
			)
		)
		(property "Value" ""
			(at 0 0 90)
			(layer "F.Fab")
			(effects
				(font
					(size 1.27 1.27)
				)
			)
		)
		(duplicate_pad_numbers_are_jumpers no)
		(fp_line
			(start 0.7874 -0.4064)
			(end 0.7874 0.4064)
			(stroke
				(width 0.1524)
				(type default)
			)
			(layer "F.SilkS")
		)
		(fp_line
			(start -0.7874 -0.4064)
			(end 0.7874 -0.4064)
			(stroke
				(width 0.1524)
				(type default)
			)
			(layer "F.SilkS")
		)
		(fp_line
			(start 0.7874 0.4064)
			(end -0.7874 0.4064)
			(stroke
				(width 0.1524)
				(type default)
			)
			(layer "F.SilkS")
		)
		(fp_line
			(start -0.7874 0.4064)
			(end -0.7874 -0.4064)
			(stroke
				(width 0.1524)
				(type default)
			)
			(layer "F.SilkS")
		)
		(fp_line
			(start -0.12065 -0.305054)
			(end -0.12065 -0.2794)
			(stroke
				(width 0.1)
				(type default)
			)
			(layer "F.Fab")
		)
		(fp_line
			(start -0.67945 -0.305054)
			(end -0.12065 -0.305054)
			(stroke
				(width 0.1)
				(type default)
			)
			(layer "F.Fab")
		)
		(fp_line
			(start 0.67945 -0.3048)
			(end 0.67945 0.3048)
			(stroke
				(width 0.1)
				(type default)
			)
			(layer "F.Fab")
		)
		(fp_line
			(start 0.12065 -0.3048)
			(end 0.67945 -0.3048)
			(stroke
				(width 0.1)
				(type default)
			)
			(layer "F.Fab")
		)
		(fp_line
			(start 0.12065 -0.2794)
			(end 0.12065 -0.3048)
			(stroke
				(width 0.1)
				(type default)
			)
			(layer "F.Fab")
		)
		(fp_line
			(start -0.12065 -0.2794)
			(end 0.12065 -0.2794)
			(stroke
				(width 0.1)
				(type default)
			)
			(layer "F.Fab")
		)
		(fp_line
			(start 0.120396 0.2794)
			(end -0.12065 0.2794)
			(stroke
				(width 0.1)
				(type default)
			)
			(layer "F.Fab")
		)
		(fp_line
			(start -0.12065 0.2794)
			(end -0.12065 0.3048)
			(stroke
				(width 0.1)
				(type default)
			)
			(layer "F.Fab")
		)
		(fp_line
			(start 0.67945 0.3048)
			(end 0.120396 0.3048)
			(stroke
				(width 0.1)
				(type default)
			)
			(layer "F.Fab")
		)
		(fp_line
			(start 0.120396 0.3048)
			(end 0.120396 0.2794)
			(stroke
				(width 0.1)
				(type default)
			)
			(layer "F.Fab")
		)
		(fp_line
			(start -0.12065 0.3048)
			(end -0.67945 0.3048)
			(stroke
				(width 0.1)
				(type default)
			)
			(layer "F.Fab")
		)
		(fp_line
			(start -0.67945 0.3048)
			(end -0.67945 -0.305054)
			(stroke
				(width 0.1)
				(type default)
			)
			(layer "F.Fab")
		)
		(pad "1" smd circle
			(at -0.40005 0 90)
			(size 0 0)
			(layers "F.Cu" "F.Mask" "F.Paste")
			(net "SW_P12V_AUX_PVDDCR_CPU0_P1_FLT")
		)
		(pad "2" smd circle
			(at 0.40005 0 90)
			(size 0 0)
			(layers "F.Cu" "F.Mask" "F.Paste")
			(net "GND")
		)
	)
	(footprint ""
		(layer "F.Cu")
		(at 19.216878 -17.623536 90)
		(property "Reference" "C681"
			(at 0 0 90)
			(layer "F.SilkS")
			(hide yes)
			(effects
				(font
					(size 1.27 1.27)
				)
			)
		)
		(property "Value" ""
			(at 0 0 90)
			(layer "F.Fab")
			(effects
				(font
					(size 1.27 1.27)
				)
			)
		)
		(duplicate_pad_numbers_are_jumpers no)
		(fp_line
			(start 0.299974 -0.150114)
			(end 0.299974 0.150114)
			(stroke
				(width 0.1)
				(type default)
			)
			(layer "F.Fab")
		)
		(fp_line
			(start -0.299974 -0.150114)
			(end 0.299974 -0.150114)
			(stroke
				(width 0.1)
				(type default)
			)
			(layer "F.Fab")
		)
		(fp_line
			(start 0.299974 0.150114)
			(end -0.299974 0.150114)
			(stroke
				(width 0.1)
				(type default)
			)
			(layer "F.Fab")
		)
		(fp_line
			(start -0.299974 0.150114)
			(end -0.299974 -0.150114)
			(stroke
				(width 0.1)
				(type default)
			)
			(layer "F.Fab")
		)
		(pad "1" smd rect
			(at -0.2667 0 90)
			(size 0.3048 0.381)
			(layers "F.Cu" "F.Mask" "F.Paste")
			(net "P5E_CPU1_G1_TX_C_DP<14>")
		)
		(pad "2" smd rect
			(at 0.2667 0 90)
			(size 0.3048 0.381)
			(layers "F.Cu" "F.Mask" "F.Paste")
			(net "P5E_CPU1_G1_TX_DP<14>")
		)
	)
	(footprint ""
		(layer "F.Cu")
		(at 305.162458 -116.891308)
		(property "Reference" "R713"
			(at 0 0 0)
			(layer "F.SilkS")
			(hide yes)
			(effects
				(font
					(size 1.27 1.27)
				)
			)
		)
		(property "Value" ""
			(at 0 0 0)
			(layer "F.Fab")
			(effects
				(font
					(size 1.27 1.27)
				)
			)
		)
		(duplicate_pad_numbers_are_jumpers no)
		(fp_line
			(start -0.7874 -0.4064)
			(end 0.7874 -0.4064)
			(stroke
				(width 0.1524)
				(type default)
			)
			(layer "F.SilkS")
		)
		(fp_line
			(start -0.7874 0.4064)
			(end -0.7874 -0.4064)
			(stroke
				(width 0.1524)
				(type default)
			)
			(layer "F.SilkS")
		)
		(fp_line
			(start 0.7874 -0.4064)
			(end 0.7874 0.4064)
			(stroke
				(width 0.1524)
				(type default)
			)
			(layer "F.SilkS")
		)
		(fp_line
			(start 0.7874 0.4064)
			(end -0.7874 0.4064)
			(stroke
				(width 0.1524)
				(type default)
			)
			(layer "F.SilkS")
		)
		(fp_line
			(start -0.67945 -0.305054)
			(end -0.12065 -0.305054)
			(stroke
				(width 0.1)
				(type default)
			)
			(layer "F.Fab")
		)
		(fp_line
			(start -0.67945 0.3048)
			(end -0.67945 -0.305054)
			(stroke
				(width 0.1)
				(type default)
			)
			(layer "F.Fab")
		)
		(fp_line
			(start -0.12065 -0.305054)
			(end -0.12065 -0.2794)
			(stroke
				(width 0.1)
				(type default)
			)
			(layer "F.Fab")
		)
		(fp_line
			(start -0.12065 -0.2794)
			(end 0.12065 -0.2794)
			(stroke
				(width 0.1)
				(type default)
			)
			(layer "F.Fab")
		)
		(fp_line
			(start -0.12065 0.2794)
			(end -0.12065 0.3048)
			(stroke
				(width 0.1)
				(type default)
			)
			(layer "F.Fab")
		)
		(fp_line
			(start -0.12065 0.3048)
			(end -0.67945 0.3048)
			(stroke
				(width 0.1)
				(type default)
			)
			(layer "F.Fab")
		)
		(fp_line
			(start 0.120396 0.2794)
			(end -0.12065 0.2794)
			(stroke
				(width 0.1)
				(type default)
			)
			(layer "F.Fab")
		)
		(fp_line
			(start 0.120396 0.3048)
			(end 0.120396 0.2794)
			(stroke
				(width 0.1)
				(type default)
			)
			(layer "F.Fab")
		)
		(fp_line
			(start 0.12065 -0.3048)
			(end 0.67945 -0.3048)
			(stroke
				(width 0.1)
				(type default)
			)
			(layer "F.Fab")
		)
		(fp_line
			(start 0.12065 -0.2794)
			(end 0.12065 -0.3048)
			(stroke
				(width 0.1)
				(type default)
			)
			(layer "F.Fab")
		)
		(fp_line
			(start 0.67945 -0.3048)
			(end 0.67945 0.3048)
			(stroke
				(width 0.1)
				(type default)
			)
			(layer "F.Fab")
		)
		(fp_line
			(start 0.67945 0.3048)
			(end 0.120396 0.3048)
			(stroke
				(width 0.1)
				(type default)
			)
			(layer "F.Fab")
		)
		(pad "1" smd circle
			(at -0.40005 0)
			(size 0 0)
			(layers "F.Cu" "F.Mask" "F.Paste")
			(net "P3V3_AUX")
		)
		(pad "2" smd circle
			(at 0.40005 0)
			(size 0 0)
			(layers "F.Cu" "F.Mask" "F.Paste")
			(net "MB_FRU_ADDR2")
		)
	)
)
